# SCM (Grand Teton) — schematic netlist excerpt (pin names and nets, part order shuffled) for the footprints in the layout excerpt that follows; sources: Cadence DE-HDL packaged netlist, KiCad conversion of 12092022_DA0F0TMDCD0_F0T_Management_Board_D_brd_V3_OCP.brd

R578  Q_RES  0 5% CHIP  pkg 0402LF  page 36 : A = PWRGD_DSW_PWROK ; B = PWRGD_DSW_PWROK_R2
PC266  Q_CAP  0.1UF 25V 10% X7R  pkg 0402  page 56 : A = P1V0_AUX ; B = GND

(kicad_pcb
	(version 20260206)
	(generator "pcbnew")
	(generator_version "10.0")
	(general
		(thickness 1.6)
		(legacy_teardrops no)
	)
	(paper "A4")
	(title_block
		(title "12092022_DA0F0TMDCD0_F0T_Management_Board_D_brd_V3_OCP.brd")
		(comment 1 "Grand Teton / footprints 683-685 of 1440")
	)
	(layers
		(0 "F.Cu" signal "TOP")
		(4 "In1.Cu" signal "GND")
		(6 "In2.Cu" signal "IN1")
		(8 "In3.Cu" signal "GND1")
		(10 "In4.Cu" signal "IN2")
		(12 "In5.Cu" signal "VCC")
		(14 "In6.Cu" signal "VCC1")
		(16 "In7.Cu" signal "IN3")
		(18 "In8.Cu" signal "GND2")
		(20 "In9.Cu" signal "IN4")
		(22 "In10.Cu" signal "GND3")
		(2 "B.Cu" signal "BOTTOM")
		(9 "F.Adhes" user "F.Adhesive")
		(11 "B.Adhes" user "B.Adhesive")
		(13 "F.Paste" user "Package Geometry/Pastemask Top")
		(15 "B.Paste" user "Package Geometry/Pastemask Bottom")
		(5 "F.SilkS" user "Ref Des/Silkscreen Top")
		(7 "B.SilkS" user "Ref Des/Silkscreen Bottom")
		(1 "F.Mask" user "Board Geometry/Soldermask Top")
		(3 "B.Mask" user "Board Geometry/Soldermask Bottom")
		(17 "Dwgs.User" user "User.Drawings")
		(19 "Cmts.User" user "User.Comments")
		(21 "Eco1.User" user "User.Eco1")
		(23 "Eco2.User" user "User.Eco2")
		(25 "Edge.Cuts" user "Board Geometry/Outline")
		(27 "Margin" user)
		(31 "F.CrtYd" user "Package Geometry/Place Bound Top")
		(29 "B.CrtYd" user "Package Geometry/Place Bound Bottom")
		(35 "F.Fab" user "Ref Des/Assembly Top")
		(33 "B.Fab" user "Ref Des/Assembly Bottom")
	)
	(footprint ""
		(layer "F.Cu")
		(at 27.559 -102.743 -90)
		(property "Reference" "R578"
			(at 0 0 270)
			(layer "F.SilkS")
			(hide yes)
			(effects
				(font
					(size 1.27 1.27)
				)
			)
		)
		(property "Value" ""
			(at 0 0 270)
			(layer "F.Fab")
			(effects
				(font
					(size 1.27 1.27)
				)
			)
		)
		(duplicate_pad_numbers_are_jumpers no)
		(fp_line
			(start -0.7874 0.4064)
			(end -0.7874 -0.4064)
			(stroke
				(width 0.1524)
				(type default)
			)
			(layer "F.SilkS")
		)
		(fp_line
			(start 0.7874 0.4064)
			(end -0.7874 0.4064)
			(stroke
				(width 0.1524)
				(type default)
			)
			(layer "F.SilkS")
		)
		(fp_line
			(start -0.7874 -0.4064)
			(end 0.7874 -0.4064)
			(stroke
				(width 0.1524)
				(type default)
			)
			(layer "F.SilkS")
		)
		(fp_line
			(start 0.7874 -0.4064)
			(end 0.7874 0.4064)
			(stroke
				(width 0.1524)
				(type default)
			)
			(layer "F.SilkS")
		)
		(fp_line
			(start -0.67945 0.3048)
			(end -0.67945 -0.305054)
			(stroke
				(width 0.1)
				(type default)
			)
			(layer "F.Fab")
		)
		(fp_line
			(start -0.12065 0.3048)
			(end -0.67945 0.3048)
			(stroke
				(width 0.1)
				(type default)
			)
			(layer "F.Fab")
		)
		(fp_line
			(start 0.120396 0.3048)
			(end 0.120396 0.2794)
			(stroke
				(width 0.1)
				(type default)
			)
			(layer "F.Fab")
		)
		(fp_line
			(start 0.67945 0.3048)
			(end 0.120396 0.3048)
			(stroke
				(width 0.1)
				(type default)
			)
			(layer "F.Fab")
		)
		(fp_line
			(start -0.12065 0.2794)
			(end -0.12065 0.3048)
			(stroke
				(width 0.1)
				(type default)
			)
			(layer "F.Fab")
		)
		(fp_line
			(start 0.120396 0.2794)
			(end -0.12065 0.2794)
			(stroke
				(width 0.1)
				(type default)
			)
			(layer "F.Fab")
		)
		(fp_line
			(start -0.12065 -0.2794)
			(end 0.12065 -0.2794)
			(stroke
				(width 0.1)
				(type default)
			)
			(layer "F.Fab")
		)
		(fp_line
			(start 0.12065 -0.2794)
			(end 0.12065 -0.3048)
			(stroke
				(width 0.1)
				(type default)
			)
			(layer "F.Fab")
		)
		(fp_line
			(start 0.12065 -0.3048)
			(end 0.67945 -0.3048)
			(stroke
				(width 0.1)
				(type default)
			)
			(layer "F.Fab")
		)
		(fp_line
			(start 0.67945 -0.3048)
			(end 0.67945 0.3048)
			(stroke
				(width 0.1)
				(type default)
			)
			(layer "F.Fab")
		)
		(fp_line
			(start -0.67945 -0.305054)
			(end -0.12065 -0.305054)
			(stroke
				(width 0.1)
				(type default)
			)
			(layer "F.Fab")
		)
		(fp_line
			(start -0.12065 -0.305054)
			(end -0.12065 -0.2794)
			(stroke
				(width 0.1)
				(type default)
			)
			(layer "F.Fab")
		)
		(pad "1" smd circle
			(at -0.40005 0 270)
			(size 0 0)
			(layers "F.Cu" "F.Mask" "F.Paste")
			(net "PWRGD_DSW_PWROK")
		)
		(pad "2" smd circle
			(at 0.40005 0 270)
			(size 0 0)
			(layers "F.Cu" "F.Mask" "F.Paste")
			(net "PWRGD_DSW_PWROK_R2")
		)
	)
	(footprint ""
		(layer "F.Cu")
		(at 25.4 -24.003 90)
		(property "Reference" "PC266"
			(at 0 0 90)
			(layer "F.SilkS")
			(hide yes)
			(effects
				(font
					(size 1.27 1.27)
				)
			)
		)
		(property "Value" ""
			(at 0 0 90)
			(layer "F.Fab")
			(effects
				(font
					(size 1.27 1.27)
				)
			)
		)
		(duplicate_pad_numbers_are_jumpers no)
		(fp_line
			(start 0.7874 -0.4064)
			(end 0.7874 0.4064)
			(stroke
				(width 0.1524)
				(type default)
			)
			(layer "F.SilkS")
		)
		(fp_line
			(start -0.7874 -0.4064)
			(end 0.7874 -0.4064)
			(stroke
				(width 0.1524)
				(type default)
			)
			(layer "F.SilkS")
		)
		(fp_line
			(start 0.7874 0.4064)
			(end -0.7874 0.4064)
			(stroke
				(width 0.1524)
				(type default)
			)
			(layer "F.SilkS")
		)
		(fp_line
			(start -0.7874 0.4064)
			(end -0.7874 -0.4064)
			(stroke
				(width 0.1524)
				(type default)
			)
			(layer "F.SilkS")
		)
		(fp_line
			(start -0.12065 -0.305054)
			(end -0.12065 -0.2794)
			(stroke
				(width 0.1)
				(type default)
			)
			(layer "F.Fab")
		)
		(fp_line
			(start -0.67945 -0.305054)
			(end -0.12065 -0.305054)
			(stroke
				(width 0.1)
				(type default)
			)
			(layer "F.Fab")
		)
		(fp_line
			(start 0.67945 -0.3048)
			(end 0.67945 0.3048)
			(stroke
				(width 0.1)
				(type default)
			)
			(layer "F.Fab")
		)
		(fp_line
			(start 0.12065 -0.3048)
			(end 0.67945 -0.3048)
			(stroke
				(width 0.1)
				(type default)
			)
			(layer "F.Fab")
		)
		(fp_line
			(start 0.12065 -0.2794)
			(end 0.12065 -0.3048)
			(stroke
				(width 0.1)
				(type default)
			)
			(layer "F.Fab")
		)
		(fp_line
			(start -0.12065 -0.2794)
			(end 0.12065 -0.2794)
			(stroke
				(width 0.1)
				(type default)
			)
			(layer "F.Fab")
		)
		(fp_line
			(start 0.120396 0.2794)
			(end -0.12065 0.2794)
			(stroke
				(width 0.1)
				(type default)
			)
			(layer "F.Fab")
		)
		(fp_line
			(start -0.12065 0.2794)
			(end -0.12065 0.3048)
			(stroke
				(width 0.1)
				(type default)
			)
			(layer "F.Fab")
		)
		(fp_line
			(start 0.67945 0.3048)
			(end 0.120396 0.3048)
			(stroke
				(width 0.1)
				(type default)
			)
			(layer "F.Fab")
		)
		(fp_line
			(start 0.120396 0.3048)
			(end 0.120396 0.2794)
			(stroke
				(width 0.1)
				(type default)
			)
			(layer "F.Fab")
		)
		(fp_line
			(start -0.12065 0.3048)
			(end -0.67945 0.3048)
			(stroke
				(width 0.1)
				(type default)
			)
			(layer "F.Fab")
		)
		(fp_line
			(start -0.67945 0.3048)
			(end -0.67945 -0.305054)
			(stroke
				(width 0.1)
				(type default)
			)
			(layer "F.Fab")
		)
		(pad "1" smd circle
			(at -0.40005 0 90)
			(size 0 0)
			(layers "F.Cu" "F.Mask" "F.Paste")
			(net "P1V0_AUX")
		)
		(pad "2" smd circle
			(at 0.40005 0 90)
			(size 0 0)
			(layers "F.Cu" "F.Mask" "F.Paste")
			(net "GND")
		)
	)
	(footprint ""
		(layer "F.Cu")
		(at 78.9432 -10.668)
		(property "Reference" ""
			(at 0 0 0)
			(layer "F.SilkS")
			(hide yes)
			(effects
				(font
					(size 1.27 1.27)
				)
			)
		)
		(property "Value" ""
			(at 0 0 0)
			(layer "F.Fab")
			(effects
				(font
					(size 1.27 1.27)
				)
			)
		)
		(duplicate_pad_numbers_are_jumpers no)
		(pad "1" smd circle
			(at 0 0)
			(size 0.9906 0.9906)
			(layers "F.Cu" "F.Mask" "F.Paste")
			(net "Net_325")
		)
		(zone
			(layer "F.Cu")
			(hatch none 0.5)
			(connect_pads
				(clearance 0)
			)
			(min_thickness 0.25)
			(keepout
				(tracks not_allowed)
				(vias allowed)
				(pads allowed)
				(copperpour not_allowed)
				(footprints allowed)
			)
			(placement
				(enabled no)
				(sheetname "")
			)
			(fill
				(thermal_gap 0.5)
				(thermal_bridge_width 0.5)
				(island_removal_mode 0)
			)
			(polygon
				(pts
					(arc
						(start 80.5688 -10.668)
						(mid 77.3176 -10.668)
						(end 80.5688 -10.668)
					)
				)
			)
		)
	)
)
